(kicad_pcb
	(version 20260206)
	(generator "pcbnew")
	(generator_version "10.0")
	(general
		(thickness 1.6)
		(legacy_teardrops no)
	)
	(paper "A4")
	(title_block
		(title "04192023_DAF0TMB3IC0_F0TG_MB_C_brd_V02_OCP.brd")
		(comment 1 "Grand Teton / footprints 8090-8096 of 8354")
	)
	(layers
		(0 "F.Cu" signal "TOP")
		(4 "In1.Cu" signal "GND")
		(6 "In2.Cu" signal "IN1")
		(8 "In3.Cu" signal "GND1")
		(10 "In4.Cu" signal "IN2")
		(12 "In5.Cu" signal "GND2")
		(14 "In6.Cu" signal "IN3")
		(16 "In7.Cu" signal "GND3")
		(18 "In8.Cu" signal "VCC")
		(20 "In9.Cu" signal "VCC1")
		(22 "In10.Cu" signal "GND4")
		(24 "In11.Cu" signal "IN4")
		(26 "In12.Cu" signal "GND5")
		(28 "In13.Cu" signal "IN5")
		(30 "In14.Cu" signal "GND6")
		(32 "In15.Cu" signal "IN6")
		(34 "In16.Cu" signal "GND7")
		(2 "B.Cu" signal "BOTTOM")
		(9 "F.Adhes" user "F.Adhesive")
		(11 "B.Adhes" user "B.Adhesive")
		(13 "F.Paste" user "Package Geometry/Pastemask Top")
		(15 "B.Paste" user "Package Geometry/Pastemask Bottom")
		(5 "F.SilkS" user "Ref Des/Silkscreen Top")
		(7 "B.SilkS" user "Ref Des/Silkscreen Bottom")
		(1 "F.Mask" user "Board Geometry/Soldermask Top")
		(3 "B.Mask" user "Board Geometry/Soldermask Bottom")
		(17 "Dwgs.User" user "User.Drawings")
		(19 "Cmts.User" user "User.Comments")
		(21 "Eco1.User" user "User.Eco1")
		(23 "Eco2.User" user "User.Eco2")
		(25 "Edge.Cuts" user "Board Geometry/Outline")
		(27 "Margin" user)
		(31 "F.CrtYd" user "Package Geometry/Place Bound Top")
		(29 "B.CrtYd" user "Package Geometry/Place Bound Bottom")
		(35 "F.Fab" user "Ref Des/Assembly Top")
		(33 "B.Fab" user "Ref Des/Assembly Bottom")
	)
	(footprint ""
		(layer "B.Cu")
		(at 334.69707 -328.219054 -90)
		(property "Reference" "PC103"
			(at 10.084054 -0.93726 270)
			(unlocked yes)
			(layer "B.SilkS")
			(effects
				(font
					(size 0.7874 0.5842)
					(thickness 0.1524)
				)
				(justify left mirror)
			)
		)
		(property "Value" ""
			(at 0 0 90)
			(layer "B.Fab")
			(effects
				(font
					(size 1.27 1.27)
				)
				(justify mirror)
			)
		)
		(duplicate_pad_numbers_are_jumpers no)
		(fp_line
			(start -4.533392 2.249932)
			(end 4.533392 2.249932)
			(stroke
				(width 0.1524)
				(type default)
			)
			(layer "B.SilkS")
		)
		(fp_line
			(start 4.533392 2.249932)
			(end 4.533392 -2.249932)
			(stroke
				(width 0.1524)
				(type default)
			)
			(layer "B.SilkS")
		)
		(fp_line
			(start -4.533392 -2.249932)
			(end -4.533392 2.249932)
			(stroke
				(width 0.1524)
				(type default)
			)
			(layer "B.SilkS")
		)
		(fp_line
			(start 4.533392 -2.249932)
			(end -4.533392 -2.249932)
			(stroke
				(width 0.1524)
				(type default)
			)
			(layer "B.SilkS")
		)
		(fp_rect
			(start 5.39242 2.326132)
			(end 4.533392 -2.326132)
			(stroke
				(width 0)
				(type default)
			)
			(fill yes)
			(layer "B.SilkS")
		)
		(fp_line
			(start -3.750056 2.249932)
			(end 3.750056 2.249932)
			(stroke
				(width 0.1)
				(type default)
			)
			(layer "B.Fab")
		)
		(fp_line
			(start 3.750056 2.249932)
			(end 3.750056 -2.249932)
			(stroke
				(width 0.1)
				(type default)
			)
			(layer "B.Fab")
		)
		(fp_line
			(start -3.750056 -2.249932)
			(end -3.750056 2.249932)
			(stroke
				(width 0.1)
				(type default)
			)
			(layer "B.Fab")
		)
		(fp_line
			(start 3.750056 -2.249932)
			(end -3.750056 -2.249932)
			(stroke
				(width 0.1)
				(type default)
			)
			(layer "B.Fab")
		)
		(fp_text user "+"
			(at 6.381242 0.548386 180)
			(unlocked yes)
			(layer "B.SilkS")
			(effects
				(font
					(size 1.905 1.4224)
					(thickness 0.1524)
				)
				(justify left mirror)
			)
		)
		(fp_text user "-"
			(at -4.8514 -0.14605 270)
			(unlocked yes)
			(layer "B.SilkS")
			(effects
				(font
					(size 1.905 1.4224)
					(thickness 0.1524)
				)
				(justify left mirror)
			)
		)
		(fp_text user "+"
			(at 6.322314 0.786384 180)
			(unlocked yes)
			(layer "B.Fab")
			(effects
				(font
					(size 1.905 1.4224)
					(thickness 0.1524)
				)
				(justify left mirror)
			)
		)
		(fp_text user "-"
			(at -4.8514 -0.14605 270)
			(unlocked yes)
			(layer "B.Fab")
			(effects
				(font
					(size 1.905 1.4224)
					(thickness 0.1524)
				)
				(justify left mirror)
			)
		)
		(pad "1" smd rect
			(at 3.199892 0 90)
			(size 2.413 2.8194)
			(layers "B.Cu" "B.Mask" "B.Paste")
			(net "PVDDCR_CPU1_P0")
		)
		(pad "2" smd rect
			(at -3.199892 0 90)
			(size 2.413 2.8194)
			(layers "B.Cu" "B.Mask" "B.Paste")
			(net "GND")
		)
	)
	(footprint ""
		(layer "B.Cu")
		(at 341.918798 -398.942052 90)
		(property "Reference" "C651"
			(at 0 0 90)
			(layer "B.SilkS")
			(hide yes)
			(effects
				(font
					(size 1.27 1.27)
				)
				(justify mirror)
			)
		)
		(property "Value" ""
			(at 0 0 90)
			(layer "B.Fab")
			(effects
				(font
					(size 1.27 1.27)
				)
				(justify mirror)
			)
		)
		(duplicate_pad_numbers_are_jumpers no)
		(fp_line
			(start 0.7874 -0.4064)
			(end -0.7874 -0.4064)
			(stroke
				(width 0.1524)
				(type default)
			)
			(layer "B.SilkS")
		)
		(fp_line
			(start -0.7874 -0.4064)
			(end -0.7874 0.4064)
			(stroke
				(width 0.1524)
				(type default)
			)
			(layer "B.SilkS")
		)
		(fp_line
			(start 0.7874 0.4064)
			(end 0.7874 -0.4064)
			(stroke
				(width 0.1524)
				(type default)
			)
			(layer "B.SilkS")
		)
		(fp_line
			(start -0.7874 0.4064)
			(end 0.7874 0.4064)
			(stroke
				(width 0.1524)
				(type default)
			)
			(layer "B.SilkS")
		)
		(fp_line
			(start 0.67945 -0.305054)
			(end 0.12065 -0.305054)
			(stroke
				(width 0.1)
				(type default)
			)
			(layer "B.Fab")
		)
		(fp_line
			(start 0.12065 -0.305054)
			(end 0.12065 -0.2794)
			(stroke
				(width 0.1)
				(type default)
			)
			(layer "B.Fab")
		)
		(fp_line
			(start -0.12065 -0.3048)
			(end -0.67945 -0.3048)
			(stroke
				(width 0.1)
				(type default)
			)
			(layer "B.Fab")
		)
		(fp_line
			(start -0.67945 -0.3048)
			(end -0.67945 0.3048)
			(stroke
				(width 0.1)
				(type default)
			)
			(layer "B.Fab")
		)
		(fp_line
			(start 0.12065 -0.2794)
			(end -0.12065 -0.2794)
			(stroke
				(width 0.1)
				(type default)
			)
			(layer "B.Fab")
		)
		(fp_line
			(start -0.12065 -0.2794)
			(end -0.12065 -0.3048)
			(stroke
				(width 0.1)
				(type default)
			)
			(layer "B.Fab")
		)
		(fp_line
			(start 0.12065 0.2794)
			(end 0.12065 0.3048)
			(stroke
				(width 0.1)
				(type default)
			)
			(layer "B.Fab")
		)
		(fp_line
			(start -0.120396 0.2794)
			(end 0.12065 0.2794)
			(stroke
				(width 0.1)
				(type default)
			)
			(layer "B.Fab")
		)
		(fp_line
			(start 0.67945 0.3048)
			(end 0.67945 -0.305054)
			(stroke
				(width 0.1)
				(type default)
			)
			(layer "B.Fab")
		)
		(fp_line
			(start 0.12065 0.3048)
			(end 0.67945 0.3048)
			(stroke
				(width 0.1)
				(type default)
			)
			(layer "B.Fab")
		)
		(fp_line
			(start -0.120396 0.3048)
			(end -0.120396 0.2794)
			(stroke
				(width 0.1)
				(type default)
			)
			(layer "B.Fab")
		)
		(fp_line
			(start -0.67945 0.3048)
			(end -0.120396 0.3048)
			(stroke
				(width 0.1)
				(type default)
			)
			(layer "B.Fab")
		)
		(pad "1" smd circle
			(at 0.40005 0 270)
			(size 0 0)
			(layers "B.Cu" "B.Mask" "B.Paste")
			(net "P0V9_CPU0_RT_2D")
		)
		(pad "2" smd circle
			(at -0.40005 0 270)
			(size 0 0)
			(layers "B.Cu" "B.Mask" "B.Paste")
			(net "GND")
		)
	)
	(footprint ""
		(layer "B.Cu")
		(at 304.419 -359.283 180)
		(property "Reference" "R8065"
			(at 0 0 0)
			(layer "B.SilkS")
			(hide yes)
			(effects
				(font
					(size 1.27 1.27)
				)
				(justify mirror)
			)
		)
		(property "Value" ""
			(at 0 0 0)
			(layer "B.Fab")
			(effects
				(font
					(size 1.27 1.27)
				)
				(justify mirror)
			)
		)
		(duplicate_pad_numbers_are_jumpers no)
		(fp_line
			(start 0.7874 0.4064)
			(end 0.7874 -0.4064)
			(stroke
				(width 0.1524)
				(type default)
			)
			(layer "B.SilkS")
		)
		(fp_line
			(start 0.7874 -0.4064)
			(end -0.7874 -0.4064)
			(stroke
				(width 0.1524)
				(type default)
			)
			(layer "B.SilkS")
		)
		(fp_line
			(start -0.7874 0.4064)
			(end 0.7874 0.4064)
			(stroke
				(width 0.1524)
				(type default)
			)
			(layer "B.SilkS")
		)
		(fp_line
			(start -0.7874 -0.4064)
			(end -0.7874 0.4064)
			(stroke
				(width 0.1524)
				(type default)
			)
			(layer "B.SilkS")
		)
		(fp_line
			(start 0.67945 0.3048)
			(end 0.67945 -0.305054)
			(stroke
				(width 0.1)
				(type default)
			)
			(layer "B.Fab")
		)
		(fp_line
			(start 0.67945 -0.305054)
			(end 0.12065 -0.305054)
			(stroke
				(width 0.1)
				(type default)
			)
			(layer "B.Fab")
		)
		(fp_line
			(start 0.12065 0.3048)
			(end 0.67945 0.3048)
			(stroke
				(width 0.1)
				(type default)
			)
			(layer "B.Fab")
		)
		(fp_line
			(start 0.12065 0.2794)
			(end 0.12065 0.3048)
			(stroke
				(width 0.1)
				(type default)
			)
			(layer "B.Fab")
		)
		(fp_line
			(start 0.12065 -0.2794)
			(end -0.12065 -0.2794)
			(stroke
				(width 0.1)
				(type default)
			)
			(layer "B.Fab")
		)
		(fp_line
			(start 0.12065 -0.305054)
			(end 0.12065 -0.2794)
			(stroke
				(width 0.1)
				(type default)
			)
			(layer "B.Fab")
		)
		(fp_line
			(start -0.120396 0.3048)
			(end -0.120396 0.2794)
			(stroke
				(width 0.1)
				(type default)
			)
			(layer "B.Fab")
		)
		(fp_line
			(start -0.120396 0.2794)
			(end 0.12065 0.2794)
			(stroke
				(width 0.1)
				(type default)
			)
			(layer "B.Fab")
		)
		(fp_line
			(start -0.12065 -0.2794)
			(end -0.12065 -0.3048)
			(stroke
				(width 0.1)
				(type default)
			)
			(layer "B.Fab")
		)
		(fp_line
			(start -0.12065 -0.3048)
			(end -0.67945 -0.3048)
			(stroke
				(width 0.1)
				(type default)
			)
			(layer "B.Fab")
		)
		(fp_line
			(start -0.67945 0.3048)
			(end -0.120396 0.3048)
			(stroke
				(width 0.1)
				(type default)
			)
			(layer "B.Fab")
		)
		(fp_line
			(start -0.67945 -0.3048)
			(end -0.67945 0.3048)
			(stroke
				(width 0.1)
				(type default)
			)
			(layer "B.Fab")
		)
		(pad "1" smd circle
			(at 0.40005 0)
			(size 0 0)
			(layers "B.Cu" "B.Mask" "B.Paste")
			(net "P3V3_AUX")
		)
		(pad "2" smd circle
			(at -0.40005 0)
			(size 0 0)
			(layers "B.Cu" "B.Mask" "B.Paste")
			(net "PWRGD_PVDDIO_P0_R")
		)
	)
	(footprint ""
		(layer "B.Cu")
		(at 373.976646 -424.523916)
		(property "Reference" "U17"
			(at 1.562354 -3.185414 0)
			(unlocked yes)
			(layer "B.SilkS")
			(effects
				(font
					(size 0.7874 0.5842)
					(thickness 0.1524)
				)
				(justify left mirror)
			)
		)
		(property "Value" ""
			(at 0 0 0)
			(layer "B.Fab")
			(effects
				(font
					(size 1.27 1.27)
				)
				(justify mirror)
			)
		)
		(duplicate_pad_numbers_are_jumpers no)
		(fp_line
			(start -1.8288 -2.500122)
			(end -1.077722 -2.500122)
			(stroke
				(width 0.1524)
				(type default)
			)
			(layer "B.SilkS")
		)
		(fp_line
			(start -1.8288 2.500122)
			(end -1.8288 -2.500122)
			(stroke
				(width 0.1524)
				(type default)
			)
			(layer "B.SilkS")
		)
		(fp_line
			(start -1.077722 -2.500122)
			(end 0 -1.4224)
			(stroke
				(width 0.1524)
				(type default)
			)
			(layer "B.SilkS")
		)
		(fp_line
			(start 0 -1.4224)
			(end 1.077722 -2.500122)
			(stroke
				(width 0.1524)
				(type default)
			)
			(layer "B.SilkS")
		)
		(fp_line
			(start 1.077722 -2.500122)
			(end 1.8288 -2.500122)
			(stroke
				(width 0.1524)
				(type default)
			)
			(layer "B.SilkS")
		)
		(fp_line
			(start 1.8288 -2.500122)
			(end 1.8288 2.500122)
			(stroke
				(width 0.1524)
				(type default)
			)
			(layer "B.SilkS")
		)
		(fp_line
			(start 1.8288 2.500122)
			(end -1.8288 2.500122)
			(stroke
				(width 0.1524)
				(type default)
			)
			(layer "B.SilkS")
		)
		(fp_poly
			(pts
				(xy 2.107438 -3.61823) (xy 3.123438 -3.61823) (xy 2.615438 -2.60223)
			)
			(stroke
				(width 0)
				(type default)
			)
			(fill yes)
			(layer "B.SilkS")
		)
		(fp_line
			(start -1.999996 -2.500122)
			(end 1.999996 -2.500122)
			(stroke
				(width 0.1)
				(type default)
			)
			(layer "B.Fab")
		)
		(fp_line
			(start -1.999996 2.500122)
			(end -1.999996 -2.500122)
			(stroke
				(width 0.1)
				(type default)
			)
			(layer "B.Fab")
		)
		(fp_line
			(start 1.999996 -2.500122)
			(end 1.999996 2.500122)
			(stroke
				(width 0.1)
				(type default)
			)
			(layer "B.Fab")
		)
		(fp_line
			(start 1.999996 2.500122)
			(end -1.999996 2.500122)
			(stroke
				(width 0.1)
				(type default)
			)
			(layer "B.Fab")
		)
		(fp_poly
			(pts
				(xy 4.5085 -2.413) (xy 4.5085 -1.397) (xy 3.4925 -1.905)
			)
			(stroke
				(width 0)
				(type default)
			)
			(fill yes)
			(layer "B.Fab")
		)
		(pad "1" smd rect
			(at 2.599944 -1.905 270)
			(size 0.889 1.27)
			(layers "B.Cu" "B.Mask" "B.Paste")
			(net "Net_10839")
		)
		(pad "2" smd rect
			(at 2.599944 -0.635 270)
			(size 0.889 1.27)
			(layers "B.Cu" "B.Mask" "B.Paste")
			(net "Net_10838")
		)
		(pad "3" smd rect
			(at 2.599944 0.635 270)
			(size 0.889 1.27)
			(layers "B.Cu" "B.Mask" "B.Paste")
			(net "U17_E2")
		)
		(pad "4" smd rect
			(at 2.599944 1.905 270)
			(size 0.889 1.27)
			(layers "B.Cu" "B.Mask" "B.Paste")
			(net "GND")
		)
		(pad "5" smd rect
			(at -2.599944 1.905 270)
			(size 0.889 1.27)
			(layers "B.Cu" "B.Mask" "B.Paste")
			(net "SMB_RT_CPU0_P3_ROM_SDA")
		)
		(pad "6" smd rect
			(at -2.599944 0.635 270)
			(size 0.889 1.27)
			(layers "B.Cu" "B.Mask" "B.Paste")
			(net "SMB_RT_CPU0_P3_ROM_SCL")
		)
		(pad "7" smd rect
			(at -2.599944 -0.635 270)
			(size 0.889 1.27)
			(layers "B.Cu" "B.Mask" "B.Paste")
			(net "GND")
		)
		(pad "8" smd rect
			(at -2.599944 -1.905 270)
			(size 0.889 1.27)
			(layers "B.Cu" "B.Mask" "B.Paste")
			(net "P1V8_CPU0_RT_1D")
		)
	)
	(footprint ""
		(layer "B.Cu")
		(at 336.046064 -396.393162 -90)
		(property "Reference" "C657"
			(at 0 0 90)
			(layer "B.SilkS")
			(hide yes)
			(effects
				(font
					(size 1.27 1.27)
				)
				(justify mirror)
			)
		)
		(property "Value" ""
			(at 0 0 90)
			(layer "B.Fab")
			(effects
				(font
					(size 1.27 1.27)
				)
				(justify mirror)
			)
		)
		(duplicate_pad_numbers_are_jumpers no)
		(fp_line
			(start -0.299974 0.150114)
			(end 0.299974 0.150114)
			(stroke
				(width 0.1)
				(type default)
			)
			(layer "B.Fab")
		)
		(fp_line
			(start 0.299974 0.150114)
			(end 0.299974 -0.150114)
			(stroke
				(width 0.1)
				(type default)
			)
			(layer "B.Fab")
		)
		(fp_line
			(start -0.299974 -0.150114)
			(end -0.299974 0.150114)
			(stroke
				(width 0.1)
				(type default)
			)
			(layer "B.Fab")
		)
		(fp_line
			(start 0.299974 -0.150114)
			(end -0.299974 -0.150114)
			(stroke
				(width 0.1)
				(type default)
			)
			(layer "B.Fab")
		)
		(pad "1" smd rect
			(at 0.2667 0 90)
			(size 0.3048 0.381)
			(layers "B.Cu" "B.Mask" "B.Paste")
			(net "P0V9_CPU0_RT1_2A")
		)
		(pad "2" smd rect
			(at -0.2667 0 90)
			(size 0.3048 0.381)
			(layers "B.Cu" "B.Mask" "B.Paste")
			(net "GND")
		)
	)
	(footprint ""
		(layer "B.Cu")
		(at 117.314726 -408.517344 90)
		(property "Reference" "C6725"
			(at 0 0 90)
			(layer "B.SilkS")
			(hide yes)
			(effects
				(font
					(size 1.27 1.27)
				)
				(justify mirror)
			)
		)
		(property "Value" ""
			(at 0 0 90)
			(layer "B.Fab")
			(effects
				(font
					(size 1.27 1.27)
				)
				(justify mirror)
			)
		)
		(duplicate_pad_numbers_are_jumpers no)
		(fp_line
			(start 0.299974 -0.150114)
			(end -0.299974 -0.150114)
			(stroke
				(width 0.1)
				(type default)
			)
			(layer "B.Fab")
		)
		(fp_line
			(start -0.299974 -0.150114)
			(end -0.299974 0.150114)
			(stroke
				(width 0.1)
				(type default)
			)
			(layer "B.Fab")
		)
		(fp_line
			(start 0.299974 0.150114)
			(end 0.299974 -0.150114)
			(stroke
				(width 0.1)
				(type default)
			)
			(layer "B.Fab")
		)
		(fp_line
			(start -0.299974 0.150114)
			(end 0.299974 0.150114)
			(stroke
				(width 0.1)
				(type default)
			)
			(layer "B.Fab")
		)
		(pad "1" smd rect
			(at 0.2667 0 270)
			(size 0.3048 0.381)
			(layers "B.Cu" "B.Mask" "B.Paste")
			(net "P5E_CPU1_P3_TX_BUF_C_DP<0>")
		)
		(pad "2" smd rect
			(at -0.2667 0 270)
			(size 0.3048 0.381)
			(layers "B.Cu" "B.Mask" "B.Paste")
			(net "P5E_CPU1_P3_TX_BUF_DP<0>")
		)
	)
	(footprint ""
		(layer "B.Cu")
		(at 153.975054 -313.96305 90)
		(property "Reference" "R575"
			(at 0 0 90)
			(layer "B.SilkS")
			(hide yes)
			(effects
				(font
					(size 1.27 1.27)
				)
				(justify mirror)
			)
		)
		(property "Value" ""
			(at 0 0 90)
			(layer "B.Fab")
			(effects
				(font
					(size 1.27 1.27)
				)
				(justify mirror)
			)
		)
		(duplicate_pad_numbers_are_jumpers no)
		(fp_line
			(start 0.7874 -0.4064)
			(end -0.7874 -0.4064)
			(stroke
				(width 0.1524)
				(type default)
			)
			(layer "B.SilkS")
		)
		(fp_line
			(start -0.7874 -0.4064)
			(end -0.7874 0.4064)
			(stroke
				(width 0.1524)
				(type default)
			)
			(layer "B.SilkS")
		)
		(fp_line
			(start 0.7874 0.4064)
			(end 0.7874 -0.4064)
			(stroke
				(width 0.1524)
				(type default)
			)
			(layer "B.SilkS")
		)
		(fp_line
			(start -0.7874 0.4064)
			(end 0.7874 0.4064)
			(stroke
				(width 0.1524)
				(type default)
			)
			(layer "B.SilkS")
		)
		(fp_line
			(start 0.67945 -0.305054)
			(end 0.12065 -0.305054)
			(stroke
				(width 0.1)
				(type default)
			)
			(layer "B.Fab")
		)
		(fp_line
			(start 0.12065 -0.305054)
			(end 0.12065 -0.2794)
			(stroke
				(width 0.1)
				(type default)
			)
			(layer "B.Fab")
		)
		(fp_line
			(start -0.12065 -0.3048)
			(end -0.67945 -0.3048)
			(stroke
				(width 0.1)
				(type default)
			)
			(layer "B.Fab")
		)
		(fp_line
			(start -0.67945 -0.3048)
			(end -0.67945 0.3048)
			(stroke
				(width 0.1)
				(type default)
			)
			(layer "B.Fab")
		)
		(fp_line
			(start 0.12065 -0.2794)
			(end -0.12065 -0.2794)
			(stroke
				(width 0.1)
				(type default)
			)
			(layer "B.Fab")
		)
		(fp_line
			(start -0.12065 -0.2794)
			(end -0.12065 -0.3048)
			(stroke
				(width 0.1)
				(type default)
			)
			(layer "B.Fab")
		)
		(fp_line
			(start 0.12065 0.2794)
			(end 0.12065 0.3048)
			(stroke
				(width 0.1)
				(type default)
			)
			(layer "B.Fab")
		)
		(fp_line
			(start -0.120396 0.2794)
			(end 0.12065 0.2794)
			(stroke
				(width 0.1)
				(type default)
			)
			(layer "B.Fab")
		)
		(fp_line
			(start 0.67945 0.3048)
			(end 0.67945 -0.305054)
			(stroke
				(width 0.1)
				(type default)
			)
			(layer "B.Fab")
		)
		(fp_line
			(start 0.12065 0.3048)
			(end 0.67945 0.3048)
			(stroke
				(width 0.1)
				(type default)
			)
			(layer "B.Fab")
		)
		(fp_line
			(start -0.120396 0.3048)
			(end -0.120396 0.2794)
			(stroke
				(width 0.1)
				(type default)
			)
			(layer "B.Fab")
		)
		(fp_line
			(start -0.67945 0.3048)
			(end -0.120396 0.3048)
			(stroke
				(width 0.1)
				(type default)
			)
			(layer "B.Fab")
		)
		(pad "1" smd circle
			(at 0.40005 0 270)
			(size 0 0)
			(layers "B.Cu" "B.Mask" "B.Paste")
			(net "XTAL_CPU1_R_X32K_X2")
		)
		(pad "2" smd circle
			(at -0.40005 0 270)
			(size 0 0)
			(layers "B.Cu" "B.Mask" "B.Paste")
			(net "XTAL_CPU1_X32K_X2")
		)
	)
)
